# BASEBOARD_FAB2 (Tioga Pass) — schematic netlist excerpt (pin names and nets, part order shuffled) for the footprints in the layout excerpt that follows; sources: Cadence DE-HDL packaged netlist, KiCad conversion of Wiwynn_Tioga_Pass_MB.brd

R6W36  RES  10.0 1% CHIP  pkg 0402  page 176 : A = SPA_MID_DBG1_TX_R ; B = SPA_MID_DBG1_TX
R2T31  RES  75 1.0% CHIP  pkg 0402  page 93 : A = H_CPU_ERR1_GTL_R_N ; B = H_CPU_ERR1_GTL_N
R785  RES  0.0 5% CHIP  pkg 0402  page 244 : A = P3E_CPU0_PE1_PCH_RXP<8> ; B = P3E_CPU0_PE1_PCH_CON_RXP<8>

(kicad_pcb
	(version 20260206)
	(generator "pcbnew")
	(generator_version "10.0")
	(general
		(thickness 1.6)
		(legacy_teardrops no)
	)
	(paper "A4")
	(title_block
		(title "Wiwynn_Tioga_Pass_MB.brd")
		(comment 1 "Tioga Pass / footprints 3136-3138 of 4770")
	)
	(layers
		(0 "F.Cu" signal "TOP")
		(4 "In1.Cu" signal "L2GND")
		(6 "In2.Cu" signal "L3")
		(8 "In3.Cu" signal "L4GND")
		(10 "In4.Cu" signal "L5")
		(12 "In5.Cu" signal "L6GND")
		(14 "In6.Cu" signal "L7VCC")
		(16 "In7.Cu" signal "L8VCC")
		(18 "In8.Cu" signal "L9GND")
		(20 "In9.Cu" signal "L10")
		(22 "In10.Cu" signal "L11GND")
		(24 "In11.Cu" signal "L12")
		(26 "In12.Cu" signal "L13GND")
		(2 "B.Cu" signal "BOTTOM")
		(9 "F.Adhes" user "F.Adhesive")
		(11 "B.Adhes" user "B.Adhesive")
		(13 "F.Paste" user "Package Geometry/Pastemask Top")
		(15 "B.Paste" user "Package Geometry/Pastemask Bottom")
		(5 "F.SilkS" user "Ref Des/Silkscreen Top")
		(7 "B.SilkS" user "Ref Des/Silkscreen Bottom")
		(1 "F.Mask" user "Board Geometry/Soldermask Top")
		(3 "B.Mask" user "Board Geometry/Soldermask Bottom")
		(17 "Dwgs.User" user "User.Drawings")
		(19 "Cmts.User" user "User.Comments")
		(21 "Eco1.User" user "User.Eco1")
		(23 "Eco2.User" user "User.Eco2")
		(25 "Edge.Cuts" user "Board Geometry/Outline")
		(27 "Margin" user)
		(31 "F.CrtYd" user "Package Geometry/Place Bound Top")
		(29 "B.CrtYd" user "Package Geometry/Place Bound Bottom")
		(35 "F.Fab" user "Ref Des/Assembly Top")
		(33 "B.Fab" user "Ref Des/Assembly Bottom")
	)
	(footprint ""
		(layer "B.Cu")
		(at 372.411752 -42.615358 180)
		(property "Reference" "R2T31"
			(at 0 0 0)
			(layer "B.SilkS")
			(hide yes)
			(effects
				(font
					(size 1.27 1.27)
				)
				(justify mirror)
			)
		)
		(property "Value" ""
			(at 0 0 0)
			(layer "B.Fab")
			(effects
				(font
					(size 1.27 1.27)
				)
				(justify mirror)
			)
		)
		(duplicate_pad_numbers_are_jumpers no)
		(fp_poly
			(pts
				(xy 0.2794 -0.1016) (xy -0.2794 -0.1016) (xy -0.2794 0.9906) (xy 0.2794 0.9906)
			)
			(stroke
				(width 0)
				(type default)
			)
			(fill no)
			(layer "B.CrtYd")
		)
		(fp_line
			(start 0.2794 0.9906)
			(end -0.2794 0.9906)
			(stroke
				(width 0.1)
				(type default)
			)
			(layer "B.Fab")
		)
		(fp_line
			(start 0.2794 -0.1016)
			(end 0.2794 0.9906)
			(stroke
				(width 0.1)
				(type default)
			)
			(layer "B.Fab")
		)
		(fp_line
			(start -0.2794 0.9906)
			(end -0.2794 -0.1016)
			(stroke
				(width 0.1)
				(type default)
			)
			(layer "B.Fab")
		)
		(fp_line
			(start -0.2794 -0.1016)
			(end 0.2794 -0.1016)
			(stroke
				(width 0.1)
				(type default)
			)
			(layer "B.Fab")
		)
		(pad "1" smd rect
			(at 0 0)
			(size 0.508 0.508)
			(layers "B.Cu" "B.Mask" "B.Paste")
			(net "H_CPU_ERR1_GTL_R_N")
		)
		(pad "2" smd rect
			(at 0 0.889)
			(size 0.508 0.508)
			(layers "B.Cu" "B.Mask" "B.Paste")
			(net "H_CPU_ERR1_GTL_N")
		)
		(zone
			(layer "B.Cu")
			(hatch none 0.5)
			(connect_pads
				(clearance 0)
			)
			(min_thickness 0.25)
			(keepout
				(tracks not_allowed)
				(vias allowed)
				(pads allowed)
				(copperpour not_allowed)
				(footprints allowed)
			)
			(placement
				(enabled no)
				(sheetname "")
			)
			(fill
				(thermal_gap 0.5)
				(thermal_bridge_width 0.5)
				(island_removal_mode 0)
			)
			(polygon
				(pts
					(xy 372.157752 -43.250358) (xy 372.665752 -43.250358) (xy 372.665752 -42.869358) (xy 372.157752 -42.869358)
				)
			)
		)
		(zone
			(layer "B.Cu")
			(hatch none 0.5)
			(connect_pads
				(clearance 0)
			)
			(min_thickness 0.25)
			(keepout
				(tracks allowed)
				(vias not_allowed)
				(pads allowed)
				(copperpour not_allowed)
				(footprints allowed)
			)
			(placement
				(enabled no)
				(sheetname "")
			)
			(fill
				(thermal_gap 0.5)
				(thermal_bridge_width 0.5)
				(island_removal_mode 0)
			)
			(polygon
				(pts
					(xy 372.157752 -42.869358) (xy 372.665752 -42.869358) (xy 372.665752 -43.250358) (xy 372.157752 -43.250358)
				)
			)
		)
	)
	(footprint ""
		(layer "B.Cu")
		(at 499.745 -153.1874 90)
		(property "Reference" "R6W36"
			(at 0.8382 -0.67818 90)
			(unlocked yes)
			(layer "B.SilkS")
			(effects
				(font
					(size 0.4064 0.254)
					(thickness 0.1524)
				)
				(justify left mirror)
			)
		)
		(property "Value" ""
			(at 0 0 90)
			(layer "B.Fab")
			(effects
				(font
					(size 1.27 1.27)
				)
				(justify mirror)
			)
		)
		(duplicate_pad_numbers_are_jumpers no)
		(fp_poly
			(pts
				(xy 0.2794 -0.1016) (xy -0.2794 -0.1016) (xy -0.2794 0.9906) (xy 0.2794 0.9906)
			)
			(stroke
				(width 0)
				(type default)
			)
			(fill no)
			(layer "B.CrtYd")
		)
		(fp_line
			(start 0.2794 -0.1016)
			(end 0.2794 0.9906)
			(stroke
				(width 0.1)
				(type default)
			)
			(layer "B.Fab")
		)
		(fp_line
			(start -0.2794 -0.1016)
			(end 0.2794 -0.1016)
			(stroke
				(width 0.1)
				(type default)
			)
			(layer "B.Fab")
		)
		(fp_line
			(start 0.2794 0.9906)
			(end -0.2794 0.9906)
			(stroke
				(width 0.1)
				(type default)
			)
			(layer "B.Fab")
		)
		(fp_line
			(start -0.2794 0.9906)
			(end -0.2794 -0.1016)
			(stroke
				(width 0.1)
				(type default)
			)
			(layer "B.Fab")
		)
		(pad "1" smd rect
			(at 0 0 270)
			(size 0.508 0.508)
			(layers "B.Cu" "B.Mask" "B.Paste")
			(net "SPA_MID_DBG1_TX_R")
		)
		(pad "2" smd rect
			(at 0 0.889 270)
			(size 0.508 0.508)
			(layers "B.Cu" "B.Mask" "B.Paste")
			(net "SPA_MID_DBG1_TX")
		)
		(zone
			(layer "B.Cu")
			(hatch none 0.5)
			(connect_pads
				(clearance 0)
			)
			(min_thickness 0.25)
			(keepout
				(tracks allowed)
				(vias not_allowed)
				(pads allowed)
				(copperpour not_allowed)
				(footprints allowed)
			)
			(placement
				(enabled no)
				(sheetname "")
			)
			(fill
				(thermal_gap 0.5)
				(thermal_bridge_width 0.5)
				(island_removal_mode 0)
			)
			(polygon
				(pts
					(xy 499.999 -153.4414) (xy 499.999 -152.9334) (xy 500.38 -152.9334) (xy 500.38 -153.4414)
				)
			)
		)
		(zone
			(layer "B.Cu")
			(hatch none 0.5)
			(connect_pads
				(clearance 0)
			)
			(min_thickness 0.25)
			(keepout
				(tracks not_allowed)
				(vias allowed)
				(pads allowed)
				(copperpour not_allowed)
				(footprints allowed)
			)
			(placement
				(enabled no)
				(sheetname "")
			)
			(fill
				(thermal_gap 0.5)
				(thermal_bridge_width 0.5)
				(island_removal_mode 0)
			)
			(polygon
				(pts
					(xy 500.38 -153.4414) (xy 500.38 -152.9334) (xy 499.999 -152.9334) (xy 499.999 -153.4414)
				)
			)
		)
	)
	(footprint ""
		(layer "B.Cu")
		(at 367.820956 -121.443242 -90)
		(property "Reference" "R785"
			(at 0.8382 -0.67818 270)
			(unlocked yes)
			(layer "B.SilkS")
			(effects
				(font
					(size 0.4064 0.254)
					(thickness 0.1524)
				)
				(justify left mirror)
			)
		)
		(property "Value" ""
			(at 0 0 90)
			(layer "B.Fab")
			(effects
				(font
					(size 1.27 1.27)
				)
				(justify mirror)
			)
		)
		(duplicate_pad_numbers_are_jumpers no)
		(fp_poly
			(pts
				(xy 0.2794 -0.1016) (xy -0.2794 -0.1016) (xy -0.2794 0.9906) (xy 0.2794 0.9906)
			)
			(stroke
				(width 0)
				(type default)
			)
			(fill no)
			(layer "B.CrtYd")
		)
		(fp_line
			(start -0.2794 0.9906)
			(end -0.2794 -0.1016)
			(stroke
				(width 0.1)
				(type default)
			)
			(layer "B.Fab")
		)
		(fp_line
			(start 0.2794 0.9906)
			(end -0.2794 0.9906)
			(stroke
				(width 0.1)
				(type default)
			)
			(layer "B.Fab")
		)
		(fp_line
			(start -0.2794 -0.1016)
			(end 0.2794 -0.1016)
			(stroke
				(width 0.1)
				(type default)
			)
			(layer "B.Fab")
		)
		(fp_line
			(start 0.2794 -0.1016)
			(end 0.2794 0.9906)
			(stroke
				(width 0.1)
				(type default)
			)
			(layer "B.Fab")
		)
		(pad "1" smd rect
			(at 0 0 90)
			(size 0.508 0.508)
			(layers "B.Cu" "B.Mask" "B.Paste")
			(net "P3E_CPU0_PE1_PCH_RXP<8>")
		)
		(pad "2" smd rect
			(at 0 0.889 90)
			(size 0.508 0.508)
			(layers "B.Cu" "B.Mask" "B.Paste")
			(net "P3E_CPU0_PE1_PCH_CON_RXP<8>")
		)
		(zone
			(layer "B.Cu")
			(hatch none 0.5)
			(connect_pads
				(clearance 0)
			)
			(min_thickness 0.25)
			(keepout
				(tracks not_allowed)
				(vias allowed)
				(pads allowed)
				(copperpour not_allowed)
				(footprints allowed)
			)
			(placement
				(enabled no)
				(sheetname "")
			)
			(fill
				(thermal_gap 0.5)
				(thermal_bridge_width 0.5)
				(island_removal_mode 0)
			)
			(polygon
				(pts
					(xy 367.185956 -121.189242) (xy 367.185956 -121.697242) (xy 367.566956 -121.697242) (xy 367.566956 -121.189242)
				)
			)
		)
		(zone
			(layer "B.Cu")
			(hatch none 0.5)
			(connect_pads
				(clearance 0)
			)
			(min_thickness 0.25)
			(keepout
				(tracks allowed)
				(vias not_allowed)
				(pads allowed)
				(copperpour not_allowed)
				(footprints allowed)
			)
			(placement
				(enabled no)
				(sheetname "")
			)
			(fill
				(thermal_gap 0.5)
				(thermal_bridge_width 0.5)
				(island_removal_mode 0)
			)
			(polygon
				(pts
					(xy 367.566956 -121.189242) (xy 367.566956 -121.697242) (xy 367.185956 -121.697242) (xy 367.185956 -121.189242)
				)
			)
		)
	)
)
